# S9S_MB_2U (Grand Teton) — schematic netlist excerpt (pin names and nets, part order shuffled) for the footprints in the layout excerpt that follows; sources: Cadence DE-HDL packaged netlist, KiCad conversion of 03242023_DA0F0TMBIJ0_F0T_Motherboard_J_brd_V01_OCP.brd

C548  Q_CAP  0.1UF 25V 10% X7R  pkg 0402  page 131 : A = JTAG_DBP_POWER_BTN_N ; B = GND
C450  Q_CAP  47UF 4V 20% X6S  pkg C0805  page 79 : A = PVCCFA_EHV_FIVRA_CPU1 ; B = GND
R2418  Q_RES  33.2 1% CHIP  pkg 0402LF  page 240 : A = SMB_S3M_CPU_3V3AUX_SDA ; B = SMB_S3M_CPU_3V3AUX_SDA_R0

(kicad_pcb
	(version 20260206)
	(generator "pcbnew")
	(generator_version "10.0")
	(general
		(thickness 1.6)
		(legacy_teardrops no)
	)
	(paper "A4")
	(title_block
		(title "03242023_DA0F0TMBIJ0_F0T_Motherboard_J_brd_V01_OCP.brd")
		(comment 1 "Grand Teton / footprints 4567-4569 of 6105")
	)
	(layers
		(0 "F.Cu" signal "TOP")
		(4 "In1.Cu" signal "GND")
		(6 "In2.Cu" signal "IN1")
		(8 "In3.Cu" signal "GND1")
		(10 "In4.Cu" signal "IN2")
		(12 "In5.Cu" signal "GND2")
		(14 "In6.Cu" signal "IN3")
		(16 "In7.Cu" signal "GND3")
		(18 "In8.Cu" signal "VCC")
		(20 "In9.Cu" signal "VCC1")
		(22 "In10.Cu" signal "GND4")
		(24 "In11.Cu" signal "IN4")
		(26 "In12.Cu" signal "GND5")
		(28 "In13.Cu" signal "IN5")
		(30 "In14.Cu" signal "GND6")
		(32 "In15.Cu" signal "IN6")
		(34 "In16.Cu" signal "GND7")
		(2 "B.Cu" signal "BOTTOM")
		(9 "F.Adhes" user "F.Adhesive")
		(11 "B.Adhes" user "B.Adhesive")
		(13 "F.Paste" user "Package Geometry/Pastemask Top")
		(15 "B.Paste" user "Package Geometry/Pastemask Bottom")
		(5 "F.SilkS" user "Ref Des/Silkscreen Top")
		(7 "B.SilkS" user "Ref Des/Silkscreen Bottom")
		(1 "F.Mask" user "Board Geometry/Soldermask Top")
		(3 "B.Mask" user "Board Geometry/Soldermask Bottom")
		(17 "Dwgs.User" user "User.Drawings")
		(19 "Cmts.User" user "User.Comments")
		(21 "Eco1.User" user "User.Eco1")
		(23 "Eco2.User" user "User.Eco2")
		(25 "Edge.Cuts" user "Board Geometry/Outline")
		(27 "Margin" user)
		(31 "F.CrtYd" user "Package Geometry/Place Bound Top")
		(29 "B.CrtYd" user "Package Geometry/Place Bound Bottom")
		(35 "F.Fab" user "Ref Des/Assembly Top")
		(33 "B.Fab" user "Ref Des/Assembly Bottom")
	)
	(footprint ""
		(layer "B.Cu")
		(at 150.900638 -13.762228 90)
		(property "Reference" "R2418"
			(at 0 0 90)
			(layer "B.SilkS")
			(hide yes)
			(effects
				(font
					(size 1.27 1.27)
				)
				(justify mirror)
			)
		)
		(property "Value" ""
			(at 0 0 90)
			(layer "B.Fab")
			(effects
				(font
					(size 1.27 1.27)
				)
				(justify mirror)
			)
		)
		(duplicate_pad_numbers_are_jumpers no)
		(fp_line
			(start 0.7874 -0.4064)
			(end -0.7874 -0.4064)
			(stroke
				(width 0.1524)
				(type default)
			)
			(layer "B.SilkS")
		)
		(fp_line
			(start -0.7874 -0.4064)
			(end -0.7874 0.4064)
			(stroke
				(width 0.1524)
				(type default)
			)
			(layer "B.SilkS")
		)
		(fp_line
			(start 0.7874 0.4064)
			(end 0.7874 -0.4064)
			(stroke
				(width 0.1524)
				(type default)
			)
			(layer "B.SilkS")
		)
		(fp_line
			(start -0.7874 0.4064)
			(end 0.7874 0.4064)
			(stroke
				(width 0.1524)
				(type default)
			)
			(layer "B.SilkS")
		)
		(fp_line
			(start 0.67945 -0.305054)
			(end 0.12065 -0.305054)
			(stroke
				(width 0.1)
				(type default)
			)
			(layer "B.Fab")
		)
		(fp_line
			(start 0.12065 -0.305054)
			(end 0.12065 -0.2794)
			(stroke
				(width 0.1)
				(type default)
			)
			(layer "B.Fab")
		)
		(fp_line
			(start -0.12065 -0.3048)
			(end -0.67945 -0.3048)
			(stroke
				(width 0.1)
				(type default)
			)
			(layer "B.Fab")
		)
		(fp_line
			(start -0.67945 -0.3048)
			(end -0.67945 0.3048)
			(stroke
				(width 0.1)
				(type default)
			)
			(layer "B.Fab")
		)
		(fp_line
			(start 0.12065 -0.2794)
			(end -0.12065 -0.2794)
			(stroke
				(width 0.1)
				(type default)
			)
			(layer "B.Fab")
		)
		(fp_line
			(start -0.12065 -0.2794)
			(end -0.12065 -0.3048)
			(stroke
				(width 0.1)
				(type default)
			)
			(layer "B.Fab")
		)
		(fp_line
			(start 0.12065 0.2794)
			(end 0.12065 0.3048)
			(stroke
				(width 0.1)
				(type default)
			)
			(layer "B.Fab")
		)
		(fp_line
			(start -0.120396 0.2794)
			(end 0.12065 0.2794)
			(stroke
				(width 0.1)
				(type default)
			)
			(layer "B.Fab")
		)
		(fp_line
			(start 0.67945 0.3048)
			(end 0.67945 -0.305054)
			(stroke
				(width 0.1)
				(type default)
			)
			(layer "B.Fab")
		)
		(fp_line
			(start 0.12065 0.3048)
			(end 0.67945 0.3048)
			(stroke
				(width 0.1)
				(type default)
			)
			(layer "B.Fab")
		)
		(fp_line
			(start -0.120396 0.3048)
			(end -0.120396 0.2794)
			(stroke
				(width 0.1)
				(type default)
			)
			(layer "B.Fab")
		)
		(fp_line
			(start -0.67945 0.3048)
			(end -0.120396 0.3048)
			(stroke
				(width 0.1)
				(type default)
			)
			(layer "B.Fab")
		)
		(pad "1" smd circle
			(at 0.40005 0 270)
			(size 0 0)
			(layers "B.Cu" "B.Mask" "B.Paste")
			(net "SMB_S3M_CPU_3V3AUX_SDA")
		)
		(pad "2" smd circle
			(at -0.40005 0 270)
			(size 0 0)
			(layers "B.Cu" "B.Mask" "B.Paste")
			(net "SMB_S3M_CPU_3V3AUX_SDA_R0")
		)
	)
	(footprint ""
		(layer "B.Cu")
		(at 404.011892 -54.754272 180)
		(property "Reference" "C548"
			(at 0 0 0)
			(layer "B.SilkS")
			(hide yes)
			(effects
				(font
					(size 1.27 1.27)
				)
				(justify mirror)
			)
		)
		(property "Value" ""
			(at 0 0 0)
			(layer "B.Fab")
			(effects
				(font
					(size 1.27 1.27)
				)
				(justify mirror)
			)
		)
		(duplicate_pad_numbers_are_jumpers no)
		(fp_line
			(start 0.7874 0.4064)
			(end 0.7874 -0.4064)
			(stroke
				(width 0.1524)
				(type default)
			)
			(layer "B.SilkS")
		)
		(fp_line
			(start 0.7874 -0.4064)
			(end -0.7874 -0.4064)
			(stroke
				(width 0.1524)
				(type default)
			)
			(layer "B.SilkS")
		)
		(fp_line
			(start -0.7874 0.4064)
			(end 0.7874 0.4064)
			(stroke
				(width 0.1524)
				(type default)
			)
			(layer "B.SilkS")
		)
		(fp_line
			(start -0.7874 -0.4064)
			(end -0.7874 0.4064)
			(stroke
				(width 0.1524)
				(type default)
			)
			(layer "B.SilkS")
		)
		(fp_line
			(start 0.67945 0.3048)
			(end 0.67945 -0.305054)
			(stroke
				(width 0.1)
				(type default)
			)
			(layer "B.Fab")
		)
		(fp_line
			(start 0.67945 -0.305054)
			(end 0.12065 -0.305054)
			(stroke
				(width 0.1)
				(type default)
			)
			(layer "B.Fab")
		)
		(fp_line
			(start 0.12065 0.3048)
			(end 0.67945 0.3048)
			(stroke
				(width 0.1)
				(type default)
			)
			(layer "B.Fab")
		)
		(fp_line
			(start 0.12065 0.2794)
			(end 0.12065 0.3048)
			(stroke
				(width 0.1)
				(type default)
			)
			(layer "B.Fab")
		)
		(fp_line
			(start 0.12065 -0.2794)
			(end -0.12065 -0.2794)
			(stroke
				(width 0.1)
				(type default)
			)
			(layer "B.Fab")
		)
		(fp_line
			(start 0.12065 -0.305054)
			(end 0.12065 -0.2794)
			(stroke
				(width 0.1)
				(type default)
			)
			(layer "B.Fab")
		)
		(fp_line
			(start -0.120396 0.3048)
			(end -0.120396 0.2794)
			(stroke
				(width 0.1)
				(type default)
			)
			(layer "B.Fab")
		)
		(fp_line
			(start -0.120396 0.2794)
			(end 0.12065 0.2794)
			(stroke
				(width 0.1)
				(type default)
			)
			(layer "B.Fab")
		)
		(fp_line
			(start -0.12065 -0.2794)
			(end -0.12065 -0.3048)
			(stroke
				(width 0.1)
				(type default)
			)
			(layer "B.Fab")
		)
		(fp_line
			(start -0.12065 -0.3048)
			(end -0.67945 -0.3048)
			(stroke
				(width 0.1)
				(type default)
			)
			(layer "B.Fab")
		)
		(fp_line
			(start -0.67945 0.3048)
			(end -0.120396 0.3048)
			(stroke
				(width 0.1)
				(type default)
			)
			(layer "B.Fab")
		)
		(fp_line
			(start -0.67945 -0.3048)
			(end -0.67945 0.3048)
			(stroke
				(width 0.1)
				(type default)
			)
			(layer "B.Fab")
		)
		(pad "1" smd circle
			(at 0.40005 0)
			(size 0 0)
			(layers "B.Cu" "B.Mask" "B.Paste")
			(net "JTAG_DBP_POWER_BTN_N")
		)
		(pad "2" smd circle
			(at -0.40005 0)
			(size 0 0)
			(layers "B.Cu" "B.Mask" "B.Paste")
			(net "GND")
		)
	)
	(footprint ""
		(layer "B.Cu")
		(at 116.40312 -259.53212 90)
		(property "Reference" "C450"
			(at 0 0 90)
			(layer "B.SilkS")
			(hide yes)
			(effects
				(font
					(size 1.27 1.27)
				)
				(justify mirror)
			)
		)
		(property "Value" ""
			(at 0 0 90)
			(layer "B.Fab")
			(effects
				(font
					(size 1.27 1.27)
				)
				(justify mirror)
			)
		)
		(duplicate_pad_numbers_are_jumpers no)
		(fp_line
			(start 1.524 -0.762)
			(end -1.524 -0.762)
			(stroke
				(width 0.1524)
				(type default)
			)
			(layer "B.SilkS")
		)
		(fp_line
			(start -1.524 -0.762)
			(end -1.524 0.762)
			(stroke
				(width 0.1524)
				(type default)
			)
			(layer "B.SilkS")
		)
		(fp_line
			(start 1.524 0.762)
			(end 1.524 -0.762)
			(stroke
				(width 0.1524)
				(type default)
			)
			(layer "B.SilkS")
		)
		(fp_line
			(start -1.524 0.762)
			(end 1.524 0.762)
			(stroke
				(width 0.1524)
				(type default)
			)
			(layer "B.SilkS")
		)
		(fp_line
			(start 1.1049 -0.724916)
			(end 1.1049 0.724916)
			(stroke
				(width 0.1)
				(type default)
			)
			(layer "B.Fab")
		)
		(fp_line
			(start -1.1049 -0.724916)
			(end 1.1049 -0.724916)
			(stroke
				(width 0.1)
				(type default)
			)
			(layer "B.Fab")
		)
		(fp_line
			(start 1.1049 0.724916)
			(end -1.1049 0.724916)
			(stroke
				(width 0.1)
				(type default)
			)
			(layer "B.Fab")
		)
		(fp_line
			(start -1.1049 0.724916)
			(end -1.1049 -0.724916)
			(stroke
				(width 0.1)
				(type default)
			)
			(layer "B.Fab")
		)
		(pad "1" smd rect
			(at 0.889 0 90)
			(size 1.016 1.27)
			(layers "B.Cu" "B.Mask" "B.Paste")
			(net "PVCCFA_EHV_FIVRA_CPU1")
		)
		(pad "2" smd rect
			(at -0.889 0 90)
			(size 1.016 1.27)
			(layers "B.Cu" "B.Mask" "B.Paste")
			(net "GND")
		)
	)
)
